(kicad_pcb
	(version 20260206)
	(generator "pcbnew")
	(generator_version "10.0")
	(general
		(thickness 1.6)
		(legacy_teardrops no)
	)
	(paper "A4")
	(title_block
		(title "Wiwynn_Tioga_Pass_MB.brd")
		(comment 1 "Tioga Pass / footprints 2150-2156 of 4770")
	)
	(layers
		(0 "F.Cu" signal "TOP")
		(4 "In1.Cu" signal "L2GND")
		(6 "In2.Cu" signal "L3")
		(8 "In3.Cu" signal "L4GND")
		(10 "In4.Cu" signal "L5")
		(12 "In5.Cu" signal "L6GND")
		(14 "In6.Cu" signal "L7VCC")
		(16 "In7.Cu" signal "L8VCC")
		(18 "In8.Cu" signal "L9GND")
		(20 "In9.Cu" signal "L10")
		(22 "In10.Cu" signal "L11GND")
		(24 "In11.Cu" signal "L12")
		(26 "In12.Cu" signal "L13GND")
		(2 "B.Cu" signal "BOTTOM")
		(9 "F.Adhes" user "F.Adhesive")
		(11 "B.Adhes" user "B.Adhesive")
		(13 "F.Paste" user "Package Geometry/Pastemask Top")
		(15 "B.Paste" user "Package Geometry/Pastemask Bottom")
		(5 "F.SilkS" user "Ref Des/Silkscreen Top")
		(7 "B.SilkS" user "Ref Des/Silkscreen Bottom")
		(1 "F.Mask" user "Board Geometry/Soldermask Top")
		(3 "B.Mask" user "Board Geometry/Soldermask Bottom")
		(17 "Dwgs.User" user "User.Drawings")
		(19 "Cmts.User" user "User.Comments")
		(21 "Eco1.User" user "User.Eco1")
		(23 "Eco2.User" user "User.Eco2")
		(25 "Edge.Cuts" user "Board Geometry/Outline")
		(27 "Margin" user)
		(31 "F.CrtYd" user "Package Geometry/Place Bound Top")
		(29 "B.CrtYd" user "Package Geometry/Place Bound Bottom")
		(35 "F.Fab" user "Ref Des/Assembly Top")
		(33 "B.Fab" user "Ref Des/Assembly Bottom")
	)
	(footprint ""
		(layer "F.Cu")
		(at 349.07728 -11.14933 -90)
		(property "Reference" "CT51"
			(at -1.72593 0.0508 0)
			(unlocked yes)
			(layer "F.SilkS")
			(effects
				(font
					(size 0.7874 0.5842)
					(thickness 0.1524)
				)
				(justify left)
			)
		)
		(property "Value" ""
			(at 0 0 270)
			(layer "F.Fab")
			(effects
				(font
					(size 1.27 1.27)
				)
			)
		)
		(duplicate_pad_numbers_are_jumpers no)
		(fp_poly
			(pts
				(xy 0.3048 -0.1016) (xy 0.3048 0.9906) (xy -0.3048 0.9906) (xy -0.3048 -0.1016)
			)
			(stroke
				(width 0)
				(type default)
			)
			(fill no)
			(layer "F.CrtYd")
		)
		(fp_line
			(start -0.3048 0.9906)
			(end 0.3048 0.9906)
			(stroke
				(width 0.1)
				(type default)
			)
			(layer "F.Fab")
		)
		(fp_line
			(start 0.3048 0.9906)
			(end 0.3048 -0.1016)
			(stroke
				(width 0.1)
				(type default)
			)
			(layer "F.Fab")
		)
		(fp_line
			(start -0.3048 -0.1016)
			(end -0.3048 0.9906)
			(stroke
				(width 0.1)
				(type default)
			)
			(layer "F.Fab")
		)
		(fp_line
			(start 0.3048 -0.1016)
			(end -0.3048 -0.1016)
			(stroke
				(width 0.1)
				(type default)
			)
			(layer "F.Fab")
		)
		(pad "1" smd rect
			(at 0 0 270)
			(size 0.508 0.508)
			(layers "F.Cu" "F.Mask" "F.Paste")
			(net "VR_PVDDQ_ABC_AIREF1")
		)
		(pad "2" smd rect
			(at 0 0.889 270)
			(size 0.508 0.508)
			(layers "F.Cu" "F.Mask" "F.Paste")
			(net "GND")
		)
		(zone
			(layer "F.Cu")
			(hatch none 0.5)
			(connect_pads
				(clearance 0)
			)
			(min_thickness 0.25)
			(keepout
				(tracks not_allowed)
				(vias allowed)
				(pads allowed)
				(copperpour not_allowed)
				(footprints allowed)
			)
			(placement
				(enabled no)
				(sheetname "")
			)
			(fill
				(thermal_gap 0.5)
				(thermal_bridge_width 0.5)
				(island_removal_mode 0)
			)
			(polygon
				(pts
					(xy 348.44228 -11.40333) (xy 348.44228 -10.89533) (xy 348.82328 -10.89533) (xy 348.82328 -11.40333)
				)
			)
		)
		(zone
			(layer "F.Cu")
			(hatch none 0.5)
			(connect_pads
				(clearance 0)
			)
			(min_thickness 0.25)
			(keepout
				(tracks allowed)
				(vias not_allowed)
				(pads allowed)
				(copperpour not_allowed)
				(footprints allowed)
			)
			(placement
				(enabled no)
				(sheetname "")
			)
			(fill
				(thermal_gap 0.5)
				(thermal_bridge_width 0.5)
				(island_removal_mode 0)
			)
			(polygon
				(pts
					(xy 348.82328 -11.40333) (xy 348.82328 -10.89533) (xy 348.44228 -10.89533) (xy 348.44228 -11.40333)
				)
			)
		)
	)
	(footprint ""
		(layer "F.Cu")
		(at 357.000048 1.999996 90)
		(property "Reference" "TH7G1"
			(at 3.624326 -3.051048 0)
			(unlocked yes)
			(layer "F.SilkS")
			(effects
				(font
					(size 0.7874 0.5842)
					(thickness 0.1524)
				)
				(justify left)
			)
		)
		(property "Value" ""
			(at 0 0 90)
			(layer "F.Fab")
			(effects
				(font
					(size 1.27 1.27)
				)
			)
		)
		(duplicate_pad_numbers_are_jumpers no)
		(fp_poly
			(pts
				(arc
					(start 3.0226 0.68834)
					(mid 3.042235 0.827855)
					(end 3.099562 0.956564)
				)
				(arc
					(start 3.099562 0.956564)
					(mid 4.012804 3.550073)
					(end 3.042158 6.12267)
				)
				(arc
					(start 3.042158 6.12267)
					(mid 0 7.518589)
					(end -3.042158 6.12267)
				)
				(arc
					(start -3.042158 6.12267)
					(mid -4.012854 3.55061)
					(end -3.100324 0.957326)
				)
				(arc
					(start -3.100324 0.957326)
					(mid -3.042498 0.827518)
					(end -3.0226 0.686816)
				)
				(arc
					(start -3.0226 -0.000254)
					(mid -2.137121 -2.137227)
					(end 0 -3.022346)
				)
				(arc
					(start 0 -3.022346)
					(mid 2.137227 -2.136973)
					(end 3.0226 0.000254)
				)
			)
			(stroke
				(width 0)
				(type default)
			)
			(fill no)
			(layer "F.CrtYd")
		)
		(pad "1" thru_hole custom
			(at 0 0 90)
			(size 2.00667 2.00667)
			(drill 0.3048)
			(layers "*.Cu" "*.Mask")
			(remove_unused_layers no)
			(net "GND")
			(clearance -0.889)
			(options
				(clearance outline)
				(anchor circle)
			)
			(primitives
				(gr_poly
					(pts
						(arc
							(start 3.042158 3.874516)
							(mid 0 5.270435)
							(end -3.042158 3.874516)
						)
						(arc
							(start -3.042158 3.874516)
							(mid -4.012854 1.302456)
							(end -3.100324 -1.290828)
						)
						(arc
							(start -3.100324 -1.290828)
							(mid -3.042498 -1.420636)
							(end -3.0226 -1.561338)
						)
						(arc
							(start -3.0226 -2.248408)
							(mid -2.137121 -4.385381)
							(end 0 -5.2705)
						)
						(arc
							(start 0 -5.2705)
							(mid 2.137227 -4.385127)
							(end 3.0226 -2.2479)
						)
						(arc
							(start 3.0226 -1.55956)
							(mid 3.04227 -1.420177)
							(end 3.099562 -1.29159)
						)
						(arc
							(start 3.099562 -1.29159)
							(mid 4.012804 1.301919)
							(end 3.042158 3.874516)
						)
					)
					(width 0)
					(fill yes)
				)
			)
		)
	)
	(footprint ""
		(layer "F.Cu")
		(at 482.03104 -51.36134)
		(property "Reference" "R9W36"
			(at -0.8382 -0.67818 0)
			(unlocked yes)
			(layer "F.SilkS")
			(effects
				(font
					(size 0.4064 0.254)
					(thickness 0.1524)
				)
				(justify left)
			)
		)
		(property "Value" ""
			(at 0 0 0)
			(layer "F.Fab")
			(effects
				(font
					(size 1.27 1.27)
				)
			)
		)
		(duplicate_pad_numbers_are_jumpers no)
		(fp_poly
			(pts
				(xy -0.2794 -0.1016) (xy 0.2794 -0.1016) (xy 0.2794 0.9906) (xy -0.2794 0.9906)
			)
			(stroke
				(width 0)
				(type default)
			)
			(fill no)
			(layer "F.CrtYd")
		)
		(fp_line
			(start -0.2794 -0.1016)
			(end -0.2794 0.9906)
			(stroke
				(width 0.1)
				(type default)
			)
			(layer "F.Fab")
		)
		(fp_line
			(start -0.2794 0.9906)
			(end 0.2794 0.9906)
			(stroke
				(width 0.1)
				(type default)
			)
			(layer "F.Fab")
		)
		(fp_line
			(start 0.2794 -0.1016)
			(end -0.2794 -0.1016)
			(stroke
				(width 0.1)
				(type default)
			)
			(layer "F.Fab")
		)
		(fp_line
			(start 0.2794 0.9906)
			(end 0.2794 -0.1016)
			(stroke
				(width 0.1)
				(type default)
			)
			(layer "F.Fab")
		)
		(pad "1" smd rect
			(at 0 0)
			(size 0.508 0.508)
			(layers "F.Cu" "F.Mask" "F.Paste")
			(net "P3V3_STBY")
		)
		(pad "2" smd rect
			(at 0 0.889)
			(size 0.508 0.508)
			(layers "F.Cu" "F.Mask" "F.Paste")
			(net "PU_DEV_OFF_N")
		)
		(zone
			(layer "F.Cu")
			(hatch none 0.5)
			(connect_pads
				(clearance 0)
			)
			(min_thickness 0.25)
			(keepout
				(tracks allowed)
				(vias not_allowed)
				(pads allowed)
				(copperpour not_allowed)
				(footprints allowed)
			)
			(placement
				(enabled no)
				(sheetname "")
			)
			(fill
				(thermal_gap 0.5)
				(thermal_bridge_width 0.5)
				(island_removal_mode 0)
			)
			(polygon
				(pts
					(xy 481.77704 -51.10734) (xy 482.28504 -51.10734) (xy 482.28504 -50.72634) (xy 481.77704 -50.72634)
				)
			)
		)
		(zone
			(layer "F.Cu")
			(hatch none 0.5)
			(connect_pads
				(clearance 0)
			)
			(min_thickness 0.25)
			(keepout
				(tracks not_allowed)
				(vias allowed)
				(pads allowed)
				(copperpour not_allowed)
				(footprints allowed)
			)
			(placement
				(enabled no)
				(sheetname "")
			)
			(fill
				(thermal_gap 0.5)
				(thermal_bridge_width 0.5)
				(island_removal_mode 0)
			)
			(polygon
				(pts
					(xy 481.77704 -50.72634) (xy 482.28504 -50.72634) (xy 482.28504 -51.10734) (xy 481.77704 -51.10734)
				)
			)
		)
	)
	(footprint ""
		(layer "F.Cu")
		(at 317.9826 -28.934918 90)
		(property "Reference" "R6F9"
			(at 0 0 90)
			(layer "F.SilkS")
			(hide yes)
			(effects
				(font
					(size 1.27 1.27)
				)
			)
		)
		(property "Value" ""
			(at 0 0 90)
			(layer "F.Fab")
			(effects
				(font
					(size 1.27 1.27)
				)
			)
		)
		(duplicate_pad_numbers_are_jumpers no)
		(fp_poly
			(pts
				(xy -0.2794 -0.1016) (xy 0.2794 -0.1016) (xy 0.2794 0.9906) (xy -0.2794 0.9906)
			)
			(stroke
				(width 0)
				(type default)
			)
			(fill no)
			(layer "F.CrtYd")
		)
		(fp_line
			(start 0.2794 -0.1016)
			(end -0.2794 -0.1016)
			(stroke
				(width 0.1)
				(type default)
			)
			(layer "F.Fab")
		)
		(fp_line
			(start -0.2794 -0.1016)
			(end -0.2794 0.9906)
			(stroke
				(width 0.1)
				(type default)
			)
			(layer "F.Fab")
		)
		(fp_line
			(start 0.2794 0.9906)
			(end 0.2794 -0.1016)
			(stroke
				(width 0.1)
				(type default)
			)
			(layer "F.Fab")
		)
		(fp_line
			(start -0.2794 0.9906)
			(end 0.2794 0.9906)
			(stroke
				(width 0.1)
				(type default)
			)
			(layer "F.Fab")
		)
		(pad "1" smd rect
			(at 0 0 90)
			(size 0.508 0.508)
			(layers "F.Cu" "F.Mask" "F.Paste")
			(net "CLK_156M_OSC_BRD_CPU0_DP")
		)
		(pad "2" smd rect
			(at 0 0.889 90)
			(size 0.508 0.508)
			(layers "F.Cu" "F.Mask" "F.Paste")
			(net "CLK_156M_OSC_CPU0_HFI_DP")
		)
		(zone
			(layer "F.Cu")
			(hatch none 0.5)
			(connect_pads
				(clearance 0)
			)
			(min_thickness 0.25)
			(keepout
				(tracks allowed)
				(vias not_allowed)
				(pads allowed)
				(copperpour not_allowed)
				(footprints allowed)
			)
			(placement
				(enabled no)
				(sheetname "")
			)
			(fill
				(thermal_gap 0.5)
				(thermal_bridge_width 0.5)
				(island_removal_mode 0)
			)
			(polygon
				(pts
					(xy 318.2366 -28.680918) (xy 318.2366 -29.188918) (xy 318.6176 -29.188918) (xy 318.6176 -28.680918)
				)
			)
		)
		(zone
			(layer "F.Cu")
			(hatch none 0.5)
			(connect_pads
				(clearance 0)
			)
			(min_thickness 0.25)
			(keepout
				(tracks not_allowed)
				(vias allowed)
				(pads allowed)
				(copperpour not_allowed)
				(footprints allowed)
			)
			(placement
				(enabled no)
				(sheetname "")
			)
			(fill
				(thermal_gap 0.5)
				(thermal_bridge_width 0.5)
				(island_removal_mode 0)
			)
			(polygon
				(pts
					(xy 318.6176 -28.680918) (xy 318.6176 -29.188918) (xy 318.2366 -29.188918) (xy 318.2366 -28.680918)
				)
			)
		)
	)
	(footprint ""
		(layer "F.Cu")
		(at 274.438872 -73.318116)
		(property "Reference" "C5D49"
			(at 0 0 0)
			(layer "F.SilkS")
			(hide yes)
			(effects
				(font
					(size 1.27 1.27)
				)
			)
		)
		(property "Value" ""
			(at 0 0 0)
			(layer "F.Fab")
			(effects
				(font
					(size 1.27 1.27)
				)
			)
		)
		(duplicate_pad_numbers_are_jumpers no)
		(fp_poly
			(pts
				(xy -0.4953 -0.2032) (xy 0.4953 -0.2032) (xy 0.4953 1.6002) (xy -0.4953 1.6002)
			)
			(stroke
				(width 0)
				(type default)
			)
			(fill no)
			(layer "F.CrtYd")
		)
		(fp_line
			(start -0.4953 -0.2032)
			(end 0.4953 -0.2032)
			(stroke
				(width 0.1)
				(type default)
			)
			(layer "F.Fab")
		)
		(fp_line
			(start -0.4953 1.6002)
			(end -0.4953 -0.2032)
			(stroke
				(width 0.1)
				(type default)
			)
			(layer "F.Fab")
		)
		(fp_line
			(start 0.4953 -0.2032)
			(end 0.4953 1.6002)
			(stroke
				(width 0.1)
				(type default)
			)
			(layer "F.Fab")
		)
		(fp_line
			(start 0.4953 1.6002)
			(end -0.4953 1.6002)
			(stroke
				(width 0.1)
				(type default)
			)
			(layer "F.Fab")
		)
		(pad "1" smd rect
			(at 0 0)
			(size 0.762 0.889)
			(layers "F.Cu" "F.Mask" "F.Paste")
			(net "PVCCMCP_CPU0")
		)
		(pad "2" smd rect
			(at 0 1.397)
			(size 0.762 0.889)
			(layers "F.Cu" "F.Mask" "F.Paste")
			(net "GND")
		)
		(zone
			(layer "F.Cu")
			(hatch none 0.5)
			(connect_pads
				(clearance 0)
			)
			(min_thickness 0.25)
			(keepout
				(tracks not_allowed)
				(vias allowed)
				(pads allowed)
				(copperpour not_allowed)
				(footprints allowed)
			)
			(placement
				(enabled no)
				(sheetname "")
			)
			(fill
				(thermal_gap 0.5)
				(thermal_bridge_width 0.5)
				(island_removal_mode 0)
			)
			(polygon
				(pts
					(xy 274.057872 -72.873616) (xy 274.819872 -72.873616) (xy 274.819872 -72.365616) (xy 274.057872 -72.365616)
				)
			)
		)
	)
	(footprint ""
		(layer "F.Cu")
		(at -3.739388 -114.954812 90)
		(property "Reference" "CR10W3"
			(at 1.06934 -0.39116 0)
			(unlocked yes)
			(layer "F.SilkS")
			(effects
				(font
					(size 0.4064 0.254)
					(thickness 0.1524)
				)
				(justify left)
			)
		)
		(property "Value" ""
			(at 0 0 90)
			(layer "F.Fab")
			(effects
				(font
					(size 1.27 1.27)
				)
			)
		)
		(duplicate_pad_numbers_are_jumpers no)
		(fp_line
			(start 0.819404 -0.070866)
			(end 0.819404 1.052576)
			(stroke
				(width 0.1524)
				(type default)
			)
			(layer "F.SilkS")
		)
		(fp_line
			(start 1.300226 1.052576)
			(end 0.338582 1.052576)
			(stroke
				(width 0.1524)
				(type default)
			)
			(layer "F.SilkS")
		)
		(fp_line
			(start 0.819404 1.052576)
			(end 1.300226 1.885442)
			(stroke
				(width 0.1524)
				(type default)
			)
			(layer "F.SilkS")
		)
		(fp_line
			(start 1.300226 1.885442)
			(end 0.819404 1.885442)
			(stroke
				(width 0.1524)
				(type default)
			)
			(layer "F.SilkS")
		)
		(fp_line
			(start 0.819404 1.885442)
			(end 0.338582 1.885442)
			(stroke
				(width 0.1524)
				(type default)
			)
			(layer "F.SilkS")
		)
		(fp_line
			(start 0.338582 1.885442)
			(end 0.819404 1.052576)
			(stroke
				(width 0.1524)
				(type default)
			)
			(layer "F.SilkS")
		)
		(fp_line
			(start 0.819404 2.797048)
			(end 0.819404 1.885442)
			(stroke
				(width 0.1524)
				(type default)
			)
			(layer "F.SilkS")
		)
		(fp_poly
			(pts
				(xy -0.67437 0.24384) (xy -0.67437 2.04216) (xy 0.67437 2.04216) (xy 0.67437 0.24384)
			)
			(stroke
				(width 0)
				(type default)
			)
			(fill no)
			(layer "F.CrtYd")
		)
		(fp_line
			(start 0.67437 0.24384)
			(end -0.67437 0.24384)
			(stroke
				(width 0.1)
				(type default)
			)
			(layer "F.Fab")
		)
		(fp_line
			(start -0.67437 0.24384)
			(end -0.67437 2.04216)
			(stroke
				(width 0.1)
				(type default)
			)
			(layer "F.Fab")
		)
		(fp_line
			(start -0.854456 0.831596)
			(end -1.8161 0.831596)
			(stroke
				(width 0.1)
				(type default)
			)
			(layer "F.Fab")
		)
		(fp_line
			(start -1.335278 0.831596)
			(end -1.335278 -0.291846)
			(stroke
				(width 0.1)
				(type default)
			)
			(layer "F.Fab")
		)
		(fp_line
			(start -1.335278 0.831596)
			(end -0.854456 1.664462)
			(stroke
				(width 0.1)
				(type default)
			)
			(layer "F.Fab")
		)
		(fp_line
			(start -0.854456 1.664462)
			(end -1.8161 1.664462)
			(stroke
				(width 0.1)
				(type default)
			)
			(layer "F.Fab")
		)
		(fp_line
			(start -1.335278 1.664462)
			(end -1.335278 2.576068)
			(stroke
				(width 0.1)
				(type default)
			)
			(layer "F.Fab")
		)
		(fp_line
			(start -1.8161 1.664462)
			(end -1.335278 0.831596)
			(stroke
				(width 0.1)
				(type default)
			)
			(layer "F.Fab")
		)
		(fp_line
			(start 0.67437 2.04216)
			(end 0.67437 0.24384)
			(stroke
				(width 0.1)
				(type default)
			)
			(layer "F.Fab")
		)
		(fp_line
			(start -0.67437 2.04216)
			(end 0.67437 2.04216)
			(stroke
				(width 0.1)
				(type default)
			)
			(layer "F.Fab")
		)
		(pad "1" smd rect
			(at 0 0 90)
			(size 0.4064 1.016)
			(layers "F.Cu" "F.Mask" "F.Paste")
			(net "PUMP_TACH1_D")
		)
		(pad "2" smd rect
			(at 0 2.286 90)
			(size 0.4064 1.016)
			(layers "F.Cu" "F.Mask" "F.Paste")
			(net "PUMP_TACH1_R")
		)
	)
	(footprint ""
		(layer "F.Cu")
		(at 349.123 -13.843 90)
		(property "Reference" "C7G3"
			(at 0 0 90)
			(layer "F.SilkS")
			(hide yes)
			(effects
				(font
					(size 1.27 1.27)
				)
			)
		)
		(property "Value" ""
			(at 0 0 90)
			(layer "F.Fab")
			(effects
				(font
					(size 1.27 1.27)
				)
			)
		)
		(duplicate_pad_numbers_are_jumpers no)
		(fp_rect
			(start -0.3048 -0.1016)
			(end 0.3048 0.9906)
			(stroke
				(width 0)
				(type default)
			)
			(fill no)
			(layer "F.CrtYd")
		)
		(fp_line
			(start 0.3048 -0.1016)
			(end -0.3048 -0.1016)
			(stroke
				(width 0.1)
				(type default)
			)
			(layer "F.Fab")
		)
		(fp_line
			(start -0.3048 -0.1016)
			(end -0.3048 0.9906)
			(stroke
				(width 0.1)
				(type default)
			)
			(layer "F.Fab")
		)
		(fp_line
			(start 0.3048 0.9906)
			(end 0.3048 -0.1016)
			(stroke
				(width 0.1)
				(type default)
			)
			(layer "F.Fab")
		)
		(fp_line
			(start -0.3048 0.9906)
			(end 0.3048 0.9906)
			(stroke
				(width 0.1)
				(type default)
			)
			(layer "F.Fab")
		)
		(pad "1" smd rect
			(at 0 0 90)
			(size 0.508 0.508)
			(layers "F.Cu" "F.Mask" "F.Paste")
			(net "A_TSENSE_PVDDQ_ABC")
		)
		(pad "2" smd rect
			(at 0 0.889 90)
			(size 0.508 0.508)
			(layers "F.Cu" "F.Mask" "F.Paste")
			(net "GND")
		)
		(zone
			(layer "F.Cu")
			(hatch none 0.5)
			(connect_pads
				(clearance 0)
			)
			(min_thickness 0.25)
			(keepout
				(tracks not_allowed)
				(vias allowed)
				(pads allowed)
				(copperpour not_allowed)
				(footprints allowed)
			)
			(placement
				(enabled no)
				(sheetname "")
			)
			(fill
				(thermal_gap 0.5)
				(thermal_bridge_width 0.5)
				(island_removal_mode 0)
			)
			(polygon
				(pts
					(xy 349.377 -13.589) (xy 349.758 -13.589) (xy 349.758 -14.097) (xy 349.377 -14.097)
				)
			)
		)
		(zone
			(layer "F.Cu")
			(hatch none 0.5)
			(connect_pads
				(clearance 0)
			)
			(min_thickness 0.25)
			(keepout
				(tracks allowed)
				(vias not_allowed)
				(pads allowed)
				(copperpour not_allowed)
				(footprints allowed)
			)
			(placement
				(enabled no)
				(sheetname "")
			)
			(fill
				(thermal_gap 0.5)
				(thermal_bridge_width 0.5)
				(island_removal_mode 0)
			)
			(polygon
				(pts
					(xy 349.377 -13.589) (xy 349.758 -13.589) (xy 349.758 -14.097) (xy 349.377 -14.097)
				)
			)
		)
	)
)
